(kicad_pcb
	(version 20260206)
	(generator "pcbnew")
	(generator_version "10.0")
	(general
		(thickness 1.6)
		(legacy_teardrops no)
	)
	(paper "A4")
	(title_block
		(title "Bryce Canyon_IOM_M2_16342-2_OCP.brd")
		(comment 1 "Bryce Canyon / footprints 792-798 of 1146")
	)
	(layers
		(0 "F.Cu" signal "TOP")
		(4 "In1.Cu" signal "L2GND")
		(6 "In2.Cu" signal "L3")
		(8 "In3.Cu" signal "L4VCC")
		(10 "In4.Cu" signal "L5VCC")
		(12 "In5.Cu" signal "L6")
		(14 "In6.Cu" signal "L7GND")
		(2 "B.Cu" signal "BOTTOM")
		(9 "F.Adhes" user "F.Adhesive")
		(11 "B.Adhes" user "B.Adhesive")
		(13 "F.Paste" user "Package Geometry/Pastemask Top")
		(15 "B.Paste" user "Package Geometry/Pastemask Bottom")
		(5 "F.SilkS" user "Ref Des/Silkscreen Top")
		(7 "B.SilkS" user "Ref Des/Silkscreen Bottom")
		(1 "F.Mask" user "Board Geometry/Soldermask Top")
		(3 "B.Mask" user "Board Geometry/Soldermask Bottom")
		(17 "Dwgs.User" user "User.Drawings")
		(19 "Cmts.User" user "User.Comments")
		(21 "Eco1.User" user "User.Eco1")
		(23 "Eco2.User" user "User.Eco2")
		(25 "Edge.Cuts" user "Board Geometry/Outline")
		(27 "Margin" user)
		(31 "F.CrtYd" user "Package Geometry/Place Bound Top")
		(29 "B.CrtYd" user "Package Geometry/Place Bound Bottom")
		(35 "F.Fab" user "Ref Des/Assembly Top")
		(33 "B.Fab" user "Ref Des/Assembly Bottom")
	)
	(footprint ""
		(layer "B.Cu")
		(at 12.11199 -139.579604 90)
		(property "Reference" "R234"
			(at 0 0 90)
			(layer "B.SilkS")
			(hide yes)
			(effects
				(font
					(size 1.27 1.27)
				)
				(justify mirror)
			)
		)
		(property "Value" "120R2F-GP"
			(at -0.064008 -3.993896 90)
			(unlocked yes)
			(layer "B.Fab")
			(hide yes)
			(effects
				(font
					(size 1.016 1.016)
					(thickness 0.1524)
				)
				(justify mirror)
			)
		)
		(property "Device Type" "R402H16"
			(at -0.064008 -5.517896 90)
			(unlocked yes)
			(layer "B.Fab")
			(hide yes)
			(effects
				(font
					(size 1.016 1.016)
					(thickness 0.1524)
				)
				(justify mirror)
			)
		)
		(duplicate_pad_numbers_are_jumpers no)
		(fp_line
			(start 0.508 -0.9398)
			(end 0.508 0.9398)
			(stroke
				(width 0.1524)
				(type default)
			)
			(layer "B.SilkS")
		)
		(fp_line
			(start -0.508 -0.9398)
			(end 0.508 -0.9398)
			(stroke
				(width 0.1524)
				(type default)
			)
			(layer "B.SilkS")
		)
		(fp_rect
			(start 0.508 0.9398)
			(end -0.508 -0.9398)
			(stroke
				(width 0)
				(type default)
			)
			(fill no)
			(layer "B.CrtYd")
		)
		(fp_rect
			(start 0.508 0.9398)
			(end -0.508 -0.9398)
			(stroke
				(width 0)
				(type default)
			)
			(fill no)
			(layer "B.Fab")
		)
		(pad "1" smd custom
			(at 0 -0.4445 270)
			(size 0.1397 0.1397)
			(layers "B.Cu" "B.Mask" "B.Paste")
			(net "MEMA_0")
			(options
				(clearance outline)
				(anchor circle)
			)
			(primitives
				(gr_poly
					(pts
						(arc
							(start -0.1778 0.2794)
							(mid -0.249642 0.249642)
							(end -0.2794 0.1778)
						)
						(arc
							(start -0.2794 -0.1778)
							(mid -0.249642 -0.249642)
							(end -0.1778 -0.2794)
						)
						(arc
							(start 0.1778 -0.2794)
							(mid 0.249642 -0.249642)
							(end 0.2794 -0.1778)
						)
						(arc
							(start 0.2794 0.1778)
							(mid 0.249642 0.249642)
							(end 0.1778 0.2794)
						)
					)
					(width 0)
					(fill yes)
				)
			)
		)
		(pad "2" smd custom
			(at 0 0.4445 270)
			(size 0.1397 0.1397)
			(layers "B.Cu" "B.Mask" "B.Paste")
			(net "P1V2_STBY")
			(options
				(clearance outline)
				(anchor circle)
			)
			(primitives
				(gr_poly
					(pts
						(arc
							(start -0.1778 0.2794)
							(mid -0.249642 0.249642)
							(end -0.2794 0.1778)
						)
						(arc
							(start -0.2794 -0.1778)
							(mid -0.249642 -0.249642)
							(end -0.1778 -0.2794)
						)
						(arc
							(start 0.1778 -0.2794)
							(mid 0.249642 -0.249642)
							(end 0.2794 -0.1778)
						)
						(arc
							(start 0.2794 0.1778)
							(mid 0.249642 0.249642)
							(end 0.1778 0.2794)
						)
					)
					(width 0)
					(fill yes)
				)
			)
		)
	)
	(footprint ""
		(layer "B.Cu")
		(at 45.5676 -134.6454 180)
		(property "Reference" "R154"
			(at 0 0 0)
			(layer "B.SilkS")
			(hide yes)
			(effects
				(font
					(size 1.27 1.27)
				)
				(justify mirror)
			)
		)
		(property "Value" "0R2J-2-GP"
			(at -0.064008 -3.993896 180)
			(unlocked yes)
			(layer "B.Fab")
			(hide yes)
			(effects
				(font
					(size 1.016 1.016)
					(thickness 0.1524)
				)
				(justify mirror)
			)
		)
		(property "Device Type" "R402H16"
			(at -0.064008 -5.517896 180)
			(unlocked yes)
			(layer "B.Fab")
			(hide yes)
			(effects
				(font
					(size 1.016 1.016)
					(thickness 0.1524)
				)
				(justify mirror)
			)
		)
		(duplicate_pad_numbers_are_jumpers no)
		(fp_line
			(start 0.508 -0.9398)
			(end 0.508 0.9398)
			(stroke
				(width 0.1524)
				(type default)
			)
			(layer "B.SilkS")
		)
		(fp_line
			(start -0.508 -0.9398)
			(end 0.508 -0.9398)
			(stroke
				(width 0.1524)
				(type default)
			)
			(layer "B.SilkS")
		)
		(fp_rect
			(start 0.508 0.9398)
			(end -0.508 -0.9398)
			(stroke
				(width 0)
				(type default)
			)
			(fill no)
			(layer "B.CrtYd")
		)
		(fp_rect
			(start 0.508 0.9398)
			(end -0.508 -0.9398)
			(stroke
				(width 0)
				(type default)
			)
			(fill no)
			(layer "B.Fab")
		)
		(pad "1" smd custom
			(at 0 -0.4445)
			(size 0.1397 0.1397)
			(layers "B.Cu" "B.Mask" "B.Paste")
			(net "I2C_IOM_SDA")
			(options
				(clearance outline)
				(anchor circle)
			)
			(primitives
				(gr_poly
					(pts
						(arc
							(start -0.1778 0.2794)
							(mid -0.249642 0.249642)
							(end -0.2794 0.1778)
						)
						(arc
							(start -0.2794 -0.1778)
							(mid -0.249642 -0.249642)
							(end -0.1778 -0.2794)
						)
						(arc
							(start 0.1778 -0.2794)
							(mid 0.249642 -0.249642)
							(end 0.2794 -0.1778)
						)
						(arc
							(start 0.2794 0.1778)
							(mid 0.249642 0.249642)
							(end 0.1778 0.2794)
						)
					)
					(width 0)
					(fill yes)
				)
			)
		)
		(pad "2" smd custom
			(at 0 0.4445)
			(size 0.1397 0.1397)
			(layers "B.Cu" "B.Mask" "B.Paste")
			(net "BMC_SMB1_DAT")
			(options
				(clearance outline)
				(anchor circle)
			)
			(primitives
				(gr_poly
					(pts
						(arc
							(start -0.1778 0.2794)
							(mid -0.249642 0.249642)
							(end -0.2794 0.1778)
						)
						(arc
							(start -0.2794 -0.1778)
							(mid -0.249642 -0.249642)
							(end -0.1778 -0.2794)
						)
						(arc
							(start 0.1778 -0.2794)
							(mid 0.249642 -0.249642)
							(end 0.2794 -0.1778)
						)
						(arc
							(start 0.2794 0.1778)
							(mid 0.249642 0.249642)
							(end 0.1778 0.2794)
						)
					)
					(width 0)
					(fill yes)
				)
			)
		)
	)
	(footprint ""
		(layer "B.Cu")
		(at 47.126652 -136.169654 90)
		(property "Reference" "R140"
			(at 0 0 90)
			(layer "B.SilkS")
			(hide yes)
			(effects
				(font
					(size 1.27 1.27)
				)
				(justify mirror)
			)
		)
		(property "Value" "100KR2F-L1-GP"
			(at -0.064008 -3.993896 90)
			(unlocked yes)
			(layer "B.Fab")
			(hide yes)
			(effects
				(font
					(size 1.016 1.016)
					(thickness 0.1524)
				)
				(justify mirror)
			)
		)
		(property "Device Type" "R402H16"
			(at -0.064008 -5.517896 90)
			(unlocked yes)
			(layer "B.Fab")
			(hide yes)
			(effects
				(font
					(size 1.016 1.016)
					(thickness 0.1524)
				)
				(justify mirror)
			)
		)
		(duplicate_pad_numbers_are_jumpers no)
		(fp_line
			(start 0.508 -0.9398)
			(end 0.508 0.9398)
			(stroke
				(width 0.1524)
				(type default)
			)
			(layer "B.SilkS")
		)
		(fp_line
			(start -0.508 -0.9398)
			(end 0.508 -0.9398)
			(stroke
				(width 0.1524)
				(type default)
			)
			(layer "B.SilkS")
		)
		(fp_rect
			(start 0.508 0.9398)
			(end -0.508 -0.9398)
			(stroke
				(width 0)
				(type default)
			)
			(fill no)
			(layer "B.CrtYd")
		)
		(fp_rect
			(start 0.508 0.9398)
			(end -0.508 -0.9398)
			(stroke
				(width 0)
				(type default)
			)
			(fill no)
			(layer "B.Fab")
		)
		(pad "1" smd custom
			(at 0 -0.4445 270)
			(size 0.1397 0.1397)
			(layers "B.Cu" "B.Mask" "B.Paste")
			(net "GND")
			(options
				(clearance outline)
				(anchor circle)
			)
			(primitives
				(gr_poly
					(pts
						(arc
							(start -0.1778 0.2794)
							(mid -0.249642 0.249642)
							(end -0.2794 0.1778)
						)
						(arc
							(start -0.2794 -0.1778)
							(mid -0.249642 -0.249642)
							(end -0.1778 -0.2794)
						)
						(arc
							(start 0.1778 -0.2794)
							(mid 0.249642 -0.249642)
							(end 0.2794 -0.1778)
						)
						(arc
							(start 0.2794 0.1778)
							(mid 0.249642 0.249642)
							(end 0.1778 0.2794)
						)
					)
					(width 0)
					(fill yes)
				)
			)
		)
		(pad "2" smd custom
			(at 0 0.4445 270)
			(size 0.1397 0.1397)
			(layers "B.Cu" "B.Mask" "B.Paste")
			(net "PD_PERST_N")
			(options
				(clearance outline)
				(anchor circle)
			)
			(primitives
				(gr_poly
					(pts
						(arc
							(start -0.1778 0.2794)
							(mid -0.249642 0.249642)
							(end -0.2794 0.1778)
						)
						(arc
							(start -0.2794 -0.1778)
							(mid -0.249642 -0.249642)
							(end -0.1778 -0.2794)
						)
						(arc
							(start 0.1778 -0.2794)
							(mid 0.249642 -0.249642)
							(end 0.2794 -0.1778)
						)
						(arc
							(start 0.2794 0.1778)
							(mid 0.249642 0.249642)
							(end 0.1778 0.2794)
						)
					)
					(width 0)
					(fill yes)
				)
			)
		)
	)
	(footprint ""
		(layer "B.Cu")
		(at 12.091924 -132.402326 90)
		(property "Reference" "R238"
			(at 0 0 90)
			(layer "B.SilkS")
			(hide yes)
			(effects
				(font
					(size 1.27 1.27)
				)
				(justify mirror)
			)
		)
		(property "Value" "120R2F-GP"
			(at -0.064008 -3.993896 90)
			(unlocked yes)
			(layer "B.Fab")
			(hide yes)
			(effects
				(font
					(size 1.016 1.016)
					(thickness 0.1524)
				)
				(justify mirror)
			)
		)
		(property "Device Type" "R402H16"
			(at -0.064008 -5.517896 90)
			(unlocked yes)
			(layer "B.Fab")
			(hide yes)
			(effects
				(font
					(size 1.016 1.016)
					(thickness 0.1524)
				)
				(justify mirror)
			)
		)
		(duplicate_pad_numbers_are_jumpers no)
		(fp_line
			(start 0.508 -0.9398)
			(end 0.508 0.9398)
			(stroke
				(width 0.1524)
				(type default)
			)
			(layer "B.SilkS")
		)
		(fp_line
			(start -0.508 -0.9398)
			(end 0.508 -0.9398)
			(stroke
				(width 0.1524)
				(type default)
			)
			(layer "B.SilkS")
		)
		(fp_rect
			(start 0.508 0.9398)
			(end -0.508 -0.9398)
			(stroke
				(width 0)
				(type default)
			)
			(fill no)
			(layer "B.CrtYd")
		)
		(fp_rect
			(start 0.508 0.9398)
			(end -0.508 -0.9398)
			(stroke
				(width 0)
				(type default)
			)
			(fill no)
			(layer "B.Fab")
		)
		(pad "1" smd custom
			(at 0 -0.4445 270)
			(size 0.1397 0.1397)
			(layers "B.Cu" "B.Mask" "B.Paste")
			(net "MEMA_2")
			(options
				(clearance outline)
				(anchor circle)
			)
			(primitives
				(gr_poly
					(pts
						(arc
							(start -0.1778 0.2794)
							(mid -0.249642 0.249642)
							(end -0.2794 0.1778)
						)
						(arc
							(start -0.2794 -0.1778)
							(mid -0.249642 -0.249642)
							(end -0.1778 -0.2794)
						)
						(arc
							(start 0.1778 -0.2794)
							(mid 0.249642 -0.249642)
							(end 0.2794 -0.1778)
						)
						(arc
							(start 0.2794 0.1778)
							(mid 0.249642 0.249642)
							(end 0.1778 0.2794)
						)
					)
					(width 0)
					(fill yes)
				)
			)
		)
		(pad "2" smd custom
			(at 0 0.4445 270)
			(size 0.1397 0.1397)
			(layers "B.Cu" "B.Mask" "B.Paste")
			(net "P1V2_STBY")
			(options
				(clearance outline)
				(anchor circle)
			)
			(primitives
				(gr_poly
					(pts
						(arc
							(start -0.1778 0.2794)
							(mid -0.249642 0.249642)
							(end -0.2794 0.1778)
						)
						(arc
							(start -0.2794 -0.1778)
							(mid -0.249642 -0.249642)
							(end -0.1778 -0.2794)
						)
						(arc
							(start 0.1778 -0.2794)
							(mid 0.249642 -0.249642)
							(end 0.2794 -0.1778)
						)
						(arc
							(start 0.2794 0.1778)
							(mid 0.249642 0.249642)
							(end 0.1778 0.2794)
						)
					)
					(width 0)
					(fill yes)
				)
			)
		)
	)
	(footprint ""
		(layer "B.Cu")
		(at 57.926478 -135.777224 -90)
		(property "Reference" "R295"
			(at 0 0 90)
			(layer "B.SilkS")
			(hide yes)
			(effects
				(font
					(size 1.27 1.27)
				)
				(justify mirror)
			)
		)
		(property "Value" "0R2J-2-GP"
			(at -0.064008 -3.993896 270)
			(unlocked yes)
			(layer "B.Fab")
			(hide yes)
			(effects
				(font
					(size 1.016 1.016)
					(thickness 0.1524)
				)
				(justify mirror)
			)
		)
		(property "Device Type" "R402H16"
			(at -0.064008 -5.517896 270)
			(unlocked yes)
			(layer "B.Fab")
			(hide yes)
			(effects
				(font
					(size 1.016 1.016)
					(thickness 0.1524)
				)
				(justify mirror)
			)
		)
		(duplicate_pad_numbers_are_jumpers no)
		(fp_line
			(start -0.508 -0.9398)
			(end 0.508 -0.9398)
			(stroke
				(width 0.1524)
				(type default)
			)
			(layer "B.SilkS")
		)
		(fp_line
			(start 0.508 -0.9398)
			(end 0.508 0.9398)
			(stroke
				(width 0.1524)
				(type default)
			)
			(layer "B.SilkS")
		)
		(fp_rect
			(start 0.508 0.9398)
			(end -0.508 -0.9398)
			(stroke
				(width 0)
				(type default)
			)
			(fill no)
			(layer "B.CrtYd")
		)
		(fp_rect
			(start 0.508 0.9398)
			(end -0.508 -0.9398)
			(stroke
				(width 0)
				(type default)
			)
			(fill no)
			(layer "B.Fab")
		)
		(pad "1" smd custom
			(at 0 -0.4445 90)
			(size 0.1397 0.1397)
			(layers "B.Cu" "B.Mask" "B.Paste")
			(net "SCC_RMT_TYPE_0")
			(options
				(clearance outline)
				(anchor circle)
			)
			(primitives
				(gr_poly
					(pts
						(arc
							(start -0.1778 0.2794)
							(mid -0.249642 0.249642)
							(end -0.2794 0.1778)
						)
						(arc
							(start -0.2794 -0.1778)
							(mid -0.249642 -0.249642)
							(end -0.1778 -0.2794)
						)
						(arc
							(start 0.1778 -0.2794)
							(mid 0.249642 -0.249642)
							(end 0.2794 -0.1778)
						)
						(arc
							(start 0.2794 0.1778)
							(mid 0.249642 0.249642)
							(end 0.1778 0.2794)
						)
					)
					(width 0)
					(fill yes)
				)
			)
		)
		(pad "2" smd custom
			(at 0 0.4445 90)
			(size 0.1397 0.1397)
			(layers "B.Cu" "B.Mask" "B.Paste")
			(net "SCC_RMT_TYPE_0_R")
			(options
				(clearance outline)
				(anchor circle)
			)
			(primitives
				(gr_poly
					(pts
						(arc
							(start -0.1778 0.2794)
							(mid -0.249642 0.249642)
							(end -0.2794 0.1778)
						)
						(arc
							(start -0.2794 -0.1778)
							(mid -0.249642 -0.249642)
							(end -0.1778 -0.2794)
						)
						(arc
							(start 0.1778 -0.2794)
							(mid 0.249642 -0.249642)
							(end 0.2794 -0.1778)
						)
						(arc
							(start 0.2794 0.1778)
							(mid 0.249642 0.249642)
							(end 0.1778 0.2794)
						)
					)
					(width 0)
					(fill yes)
				)
			)
		)
	)
	(footprint ""
		(layer "B.Cu")
		(at 75.35672 -140.859256 180)
		(property "Reference" "R380"
			(at 0 0 0)
			(layer "B.SilkS")
			(hide yes)
			(effects
				(font
					(size 1.27 1.27)
				)
				(justify mirror)
			)
		)
		(property "Value" "4K7R2F-GP"
			(at -0.064008 -3.993896 180)
			(unlocked yes)
			(layer "B.Fab")
			(hide yes)
			(effects
				(font
					(size 1.016 1.016)
					(thickness 0.1524)
				)
				(justify mirror)
			)
		)
		(property "Device Type" "R402H16"
			(at -0.064008 -5.517896 180)
			(unlocked yes)
			(layer "B.Fab")
			(hide yes)
			(effects
				(font
					(size 1.016 1.016)
					(thickness 0.1524)
				)
				(justify mirror)
			)
		)
		(duplicate_pad_numbers_are_jumpers no)
		(fp_line
			(start 0.508 -0.9398)
			(end 0.508 0.9398)
			(stroke
				(width 0.1524)
				(type default)
			)
			(layer "B.SilkS")
		)
		(fp_line
			(start -0.508 -0.9398)
			(end 0.508 -0.9398)
			(stroke
				(width 0.1524)
				(type default)
			)
			(layer "B.SilkS")
		)
		(fp_rect
			(start 0.508 0.9398)
			(end -0.508 -0.9398)
			(stroke
				(width 0)
				(type default)
			)
			(fill no)
			(layer "B.CrtYd")
		)
		(fp_rect
			(start 0.508 0.9398)
			(end -0.508 -0.9398)
			(stroke
				(width 0)
				(type default)
			)
			(fill no)
			(layer "B.Fab")
		)
		(pad "1" smd custom
			(at 0 -0.4445)
			(size 0.1397 0.1397)
			(layers "B.Cu" "B.Mask" "B.Paste")
			(net "P3V3_STBY")
			(options
				(clearance outline)
				(anchor circle)
			)
			(primitives
				(gr_poly
					(pts
						(arc
							(start -0.1778 0.2794)
							(mid -0.249642 0.249642)
							(end -0.2794 0.1778)
						)
						(arc
							(start -0.2794 -0.1778)
							(mid -0.249642 -0.249642)
							(end -0.1778 -0.2794)
						)
						(arc
							(start 0.1778 -0.2794)
							(mid 0.249642 -0.249642)
							(end 0.2794 -0.1778)
						)
						(arc
							(start 0.2794 0.1778)
							(mid 0.249642 0.249642)
							(end 0.1778 0.2794)
						)
					)
					(width 0)
					(fill yes)
				)
			)
		)
		(pad "2" smd custom
			(at 0 0.4445)
			(size 0.1397 0.1397)
			(layers "B.Cu" "B.Mask" "B.Paste")
			(net "NCSI_TXEN")
			(options
				(clearance outline)
				(anchor circle)
			)
			(primitives
				(gr_poly
					(pts
						(arc
							(start -0.1778 0.2794)
							(mid -0.249642 0.249642)
							(end -0.2794 0.1778)
						)
						(arc
							(start -0.2794 -0.1778)
							(mid -0.249642 -0.249642)
							(end -0.1778 -0.2794)
						)
						(arc
							(start 0.1778 -0.2794)
							(mid 0.249642 -0.249642)
							(end 0.2794 -0.1778)
						)
						(arc
							(start 0.2794 0.1778)
							(mid 0.249642 0.249642)
							(end 0.1778 0.2794)
						)
					)
					(width 0)
					(fill yes)
				)
			)
		)
	)
	(footprint ""
		(layer "B.Cu")
		(at 49.75098 -161.59734 90)
		(property "Reference" "R279"
			(at 0 0 90)
			(layer "B.SilkS")
			(hide yes)
			(effects
				(font
					(size 1.27 1.27)
				)
				(justify mirror)
			)
		)
		(property "Value" "0R2J-2-GP"
			(at -0.064008 -3.993896 90)
			(unlocked yes)
			(layer "B.Fab")
			(hide yes)
			(effects
				(font
					(size 1.016 1.016)
					(thickness 0.1524)
				)
				(justify mirror)
			)
		)
		(property "Device Type" "R402H16"
			(at -0.064008 -5.517896 90)
			(unlocked yes)
			(layer "B.Fab")
			(hide yes)
			(effects
				(font
					(size 1.016 1.016)
					(thickness 0.1524)
				)
				(justify mirror)
			)
		)
		(duplicate_pad_numbers_are_jumpers no)
		(fp_line
			(start 0.508 -0.9398)
			(end 0.508 0.9398)
			(stroke
				(width 0.1524)
				(type default)
			)
			(layer "B.SilkS")
		)
		(fp_line
			(start -0.508 -0.9398)
			(end 0.508 -0.9398)
			(stroke
				(width 0.1524)
				(type default)
			)
			(layer "B.SilkS")
		)
		(fp_rect
			(start 0.508 0.9398)
			(end -0.508 -0.9398)
			(stroke
				(width 0)
				(type default)
			)
			(fill no)
			(layer "B.CrtYd")
		)
		(fp_rect
			(start 0.508 0.9398)
			(end -0.508 -0.9398)
			(stroke
				(width 0)
				(type default)
			)
			(fill no)
			(layer "B.Fab")
		)
		(pad "1" smd custom
			(at 0 -0.4445 270)
			(size 0.1397 0.1397)
			(layers "B.Cu" "B.Mask" "B.Paste")
			(net "I2C_MEZZ_OOB_SCL")
			(options
				(clearance outline)
				(anchor circle)
			)
			(primitives
				(gr_poly
					(pts
						(arc
							(start -0.1778 0.2794)
							(mid -0.249642 0.249642)
							(end -0.2794 0.1778)
						)
						(arc
							(start -0.2794 -0.1778)
							(mid -0.249642 -0.249642)
							(end -0.1778 -0.2794)
						)
						(arc
							(start 0.1778 -0.2794)
							(mid 0.249642 -0.249642)
							(end 0.2794 -0.1778)
						)
						(arc
							(start 0.2794 0.1778)
							(mid 0.249642 0.249642)
							(end 0.1778 0.2794)
						)
					)
					(width 0)
					(fill yes)
				)
			)
		)
		(pad "2" smd custom
			(at 0 0.4445 270)
			(size 0.1397 0.1397)
			(layers "B.Cu" "B.Mask" "B.Paste")
			(net "BMC_SMB5_CLK")
			(options
				(clearance outline)
				(anchor circle)
			)
			(primitives
				(gr_poly
					(pts
						(arc
							(start -0.1778 0.2794)
							(mid -0.249642 0.249642)
							(end -0.2794 0.1778)
						)
						(arc
							(start -0.2794 -0.1778)
							(mid -0.249642 -0.249642)
							(end -0.1778 -0.2794)
						)
						(arc
							(start 0.1778 -0.2794)
							(mid 0.249642 -0.249642)
							(end 0.2794 -0.1778)
						)
						(arc
							(start 0.2794 0.1778)
							(mid 0.249642 0.249642)
							(end 0.1778 0.2794)
						)
					)
					(width 0)
					(fill yes)
				)
			)
		)
	)
)
